(kicad_pcb
	(version 20260206)
	(generator "pcbnew")
	(generator_version "10.0")
	(general
		(thickness 1.6)
		(legacy_teardrops no)
	)
	(paper "A4")
	(title_block
		(title "baseboard — 13948-1b.1110WZS1818.brd")
		(comment 1 "Honey Badger (Wiwynn) / footprints 881-885 of 2523")
	)
	(layers
		(0 "F.Cu" signal "TOP")
		(4 "In1.Cu" signal "L2GND")
		(6 "In2.Cu" signal "L3")
		(8 "In3.Cu" signal "L4VCC")
		(10 "In4.Cu" signal "L5VCC")
		(12 "In5.Cu" signal "L6")
		(14 "In6.Cu" signal "L7GND")
		(2 "B.Cu" signal "BOTTOM")
		(9 "F.Adhes" user "F.Adhesive")
		(11 "B.Adhes" user "B.Adhesive")
		(13 "F.Paste" user "Package Geometry/Pastemask Top")
		(15 "B.Paste" user "Package Geometry/Pastemask Bottom")
		(5 "F.SilkS" user "Ref Des/Silkscreen Top")
		(7 "B.SilkS" user "Ref Des/Silkscreen Bottom")
		(1 "F.Mask" user "Board Geometry/Soldermask Top")
		(3 "B.Mask" user "Board Geometry/Soldermask Bottom")
		(17 "Dwgs.User" user "User.Drawings")
		(19 "Cmts.User" user "User.Comments")
		(21 "Eco1.User" user "User.Eco1")
		(23 "Eco2.User" user "User.Eco2")
		(25 "Edge.Cuts" user "Board Geometry/Outline")
		(27 "Margin" user)
		(31 "F.CrtYd" user "Package Geometry/Place Bound Top")
		(29 "B.CrtYd" user "Package Geometry/Place Bound Bottom")
		(35 "F.Fab" user "Ref Des/Assembly Top")
		(33 "B.Fab" user "Ref Des/Assembly Bottom")
	)
	(footprint ""
		(layer "F.Cu")
		(at 169.789348 -122.545856 180)
		(property "Reference" "PR163"
			(at 0 0 180)
			(layer "F.SilkS")
			(hide yes)
			(effects
				(font
					(size 1.27 1.27)
				)
			)
		)
		(property "Value" "100KR2F-L1-GP"
			(at 0.064008 -3.993896 180)
			(unlocked yes)
			(layer "F.Fab")
			(hide yes)
			(effects
				(font
					(size 1.016 1.016)
					(thickness 0.1524)
				)
			)
		)
		(property "Device Type" "R402H16"
			(at 0.064008 -5.517896 180)
			(unlocked yes)
			(layer "F.Fab")
			(hide yes)
			(effects
				(font
					(size 1.016 1.016)
					(thickness 0.1524)
				)
			)
		)
		(duplicate_pad_numbers_are_jumpers no)
		(fp_line
			(start 0.508 -0.9398)
			(end -0.508 -0.9398)
			(stroke
				(width 0.1524)
				(type default)
			)
			(layer "F.SilkS")
		)
		(fp_line
			(start -0.508 -0.9398)
			(end -0.508 0.9398)
			(stroke
				(width 0.1524)
				(type default)
			)
			(layer "F.SilkS")
		)
		(fp_rect
			(start -0.508 0.9398)
			(end 0.508 -0.9398)
			(stroke
				(width 0)
				(type default)
			)
			(fill no)
			(layer "F.CrtYd")
		)
		(fp_rect
			(start -0.508 0.9398)
			(end 0.508 -0.9398)
			(stroke
				(width 0)
				(type default)
			)
			(fill no)
			(layer "F.Fab")
		)
		(pad "1" smd custom
			(at 0 -0.4445 180)
			(size 0.1397 0.1397)
			(layers "F.Cu" "F.Mask" "F.Paste")
			(net "P0V9_E_MODE")
			(options
				(clearance outline)
				(anchor circle)
			)
			(primitives
				(gr_poly
					(pts
						(arc
							(start -0.1778 -0.2794)
							(mid -0.249642 -0.249642)
							(end -0.2794 -0.1778)
						)
						(arc
							(start -0.2794 0.1778)
							(mid -0.249642 0.249642)
							(end -0.1778 0.2794)
						)
						(arc
							(start 0.1778 0.2794)
							(mid 0.249642 0.249642)
							(end 0.2794 0.1778)
						)
						(arc
							(start 0.2794 -0.1778)
							(mid 0.249642 -0.249642)
							(end 0.1778 -0.2794)
						)
					)
					(width 0)
					(fill yes)
				)
			)
		)
		(pad "2" smd custom
			(at 0 0.4445 180)
			(size 0.1397 0.1397)
			(layers "F.Cu" "F.Mask" "F.Paste")
			(net "AGND_P0V9_E")
			(options
				(clearance outline)
				(anchor circle)
			)
			(primitives
				(gr_poly
					(pts
						(arc
							(start -0.1778 -0.2794)
							(mid -0.249642 -0.249642)
							(end -0.2794 -0.1778)
						)
						(arc
							(start -0.2794 0.1778)
							(mid -0.249642 0.249642)
							(end -0.1778 0.2794)
						)
						(arc
							(start 0.1778 0.2794)
							(mid 0.249642 0.249642)
							(end 0.2794 0.1778)
						)
						(arc
							(start 0.2794 -0.1778)
							(mid 0.249642 -0.249642)
							(end 0.1778 -0.2794)
						)
					)
					(width 0)
					(fill yes)
				)
			)
		)
	)
	(footprint ""
		(layer "F.Cu")
		(at 117.964966 -43.815 -90)
		(property "Reference" "SR614"
			(at 0 0 270)
			(layer "F.SilkS")
			(hide yes)
			(effects
				(font
					(size 1.27 1.27)
				)
			)
		)
		(property "Value" "2K2R2F-GP"
			(at 0.064008 -3.993896 270)
			(unlocked yes)
			(layer "F.Fab")
			(hide yes)
			(effects
				(font
					(size 1.016 1.016)
					(thickness 0.1524)
				)
			)
		)
		(property "Device Type" "R402H16"
			(at 0.064008 -5.517896 270)
			(unlocked yes)
			(layer "F.Fab")
			(hide yes)
			(effects
				(font
					(size 1.016 1.016)
					(thickness 0.1524)
				)
			)
		)
		(duplicate_pad_numbers_are_jumpers no)
		(fp_line
			(start -0.508 -0.9398)
			(end -0.508 0.9398)
			(stroke
				(width 0.1524)
				(type default)
			)
			(layer "F.SilkS")
		)
		(fp_line
			(start 0.508 -0.9398)
			(end -0.508 -0.9398)
			(stroke
				(width 0.1524)
				(type default)
			)
			(layer "F.SilkS")
		)
		(fp_rect
			(start -0.508 0.9398)
			(end 0.508 -0.9398)
			(stroke
				(width 0)
				(type default)
			)
			(fill no)
			(layer "F.CrtYd")
		)
		(fp_rect
			(start -0.508 0.9398)
			(end 0.508 -0.9398)
			(stroke
				(width 0)
				(type default)
			)
			(fill no)
			(layer "F.Fab")
		)
		(pad "1" smd custom
			(at 0 -0.4445 270)
			(size 0.1397 0.1397)
			(layers "F.Cu" "F.Mask" "F.Paste")
			(net "P1V8_C")
			(options
				(clearance outline)
				(anchor circle)
			)
			(primitives
				(gr_poly
					(pts
						(arc
							(start -0.1778 -0.2794)
							(mid -0.249642 -0.249642)
							(end -0.2794 -0.1778)
						)
						(arc
							(start -0.2794 0.1778)
							(mid -0.249642 0.249642)
							(end -0.1778 0.2794)
						)
						(arc
							(start 0.1778 0.2794)
							(mid 0.249642 0.249642)
							(end 0.2794 0.1778)
						)
						(arc
							(start 0.2794 -0.1778)
							(mid 0.249642 -0.249642)
							(end 0.1778 -0.2794)
						)
					)
					(width 0)
					(fill yes)
				)
			)
		)
		(pad "2" smd custom
			(at 0 0.4445 270)
			(size 0.1397 0.1397)
			(layers "F.Cu" "F.Mask" "F.Paste")
			(net "SBL_SCL")
			(options
				(clearance outline)
				(anchor circle)
			)
			(primitives
				(gr_poly
					(pts
						(arc
							(start -0.1778 -0.2794)
							(mid -0.249642 -0.249642)
							(end -0.2794 -0.1778)
						)
						(arc
							(start -0.2794 0.1778)
							(mid -0.249642 0.249642)
							(end -0.1778 0.2794)
						)
						(arc
							(start 0.1778 0.2794)
							(mid 0.249642 0.249642)
							(end 0.2794 0.1778)
						)
						(arc
							(start 0.2794 -0.1778)
							(mid 0.249642 -0.249642)
							(end 0.1778 -0.2794)
						)
					)
					(width 0)
					(fill yes)
				)
			)
		)
	)
	(footprint ""
		(layer "F.Cu")
		(at 322.444872 -112.848136 180)
		(property "Reference" "PU2"
			(at 0 0 180)
			(layer "F.SilkS")
			(hide yes)
			(effects
				(font
					(size 1.27 1.27)
				)
			)
		)
		(property "Value" "TPS53318DQPR-GP"
			(at -5.022088 -6.851904 180)
			(unlocked yes)
			(layer "F.Fab")
			(hide yes)
			(effects
				(font
					(size 1.016 1.016)
					(thickness 0.1524)
				)
			)
		)
		(property "Device Type" "DFN22G6050-G6133H60"
			(at -5.022088 -8.375904 180)
			(unlocked yes)
			(layer "F.Fab")
			(hide yes)
			(effects
				(font
					(size 1.016 1.016)
					(thickness 0.1524)
				)
			)
		)
		(duplicate_pad_numbers_are_jumpers no)
		(fp_line
			(start 3.5052 3.5179)
			(end 3.5052 2.2479)
			(stroke
				(width 0.1524)
				(type default)
			)
			(layer "F.SilkS")
		)
		(fp_line
			(start 2.2352 3.5179)
			(end 3.5052 3.5179)
			(stroke
				(width 0.1524)
				(type default)
			)
			(layer "F.SilkS")
		)
		(fp_line
			(start 1.500124 3.262122)
			(end 1.500124 4.024122)
			(stroke
				(width 0.1524)
				(type default)
			)
			(layer "F.SilkS")
		)
		(fp_line
			(start 0.500126 -3.262122)
			(end 0.500126 -3.770122)
			(stroke
				(width 0.1524)
				(type default)
			)
			(layer "F.SilkS")
		)
		(fp_line
			(start -0.999998 3.262122)
			(end -0.999998 3.770122)
			(stroke
				(width 0.1524)
				(type default)
			)
			(layer "F.SilkS")
		)
		(fp_line
			(start -1.999996 -3.262122)
			(end -1.999996 -4.024122)
			(stroke
				(width 0.1524)
				(type default)
			)
			(layer "F.SilkS")
		)
		(fp_line
			(start -2.2352 -3.5179)
			(end -3.5052 -3.5179)
			(stroke
				(width 0.1524)
				(type default)
			)
			(layer "F.SilkS")
		)
		(fp_line
			(start -3.5052 3.5179)
			(end -2.2352 3.5179)
			(stroke
				(width 0.1524)
				(type default)
			)
			(layer "F.SilkS")
		)
		(fp_line
			(start -3.5052 2.2479)
			(end -3.5052 3.5179)
			(stroke
				(width 0.1524)
				(type default)
			)
			(layer "F.SilkS")
		)
		(fp_line
			(start -3.5052 -3.5179)
			(end -3.5052 -2.2479)
			(stroke
				(width 0.1524)
				(type default)
			)
			(layer "F.SilkS")
		)
		(fp_poly
			(pts
				(xy 3.5052 -3.5179) (xy 2.4765 -3.5179) (xy 3.5052 -2.4892)
			)
			(stroke
				(width 0)
				(type default)
			)
			(fill yes)
			(layer "F.SilkS")
		)
		(fp_rect
			(start -2.9972 2.5019)
			(end 2.9972 -2.5019)
			(stroke
				(width 0)
				(type default)
			)
			(fill no)
			(layer "F.CrtYd")
		)
		(fp_poly
			(pts
				(xy 3.556 -2.5019) (xy -2.9972 -2.5019) (xy -2.9972 2.5019) (xy 2.9972 2.5019) (xy 2.9972 -2.4892)
				(xy 3.556 -2.4892) (xy 3.556 3.5179) (xy -3.556 3.5179) (xy -3.556 -3.5179) (xy 3.556 -3.5179)
			)
			(stroke
				(width 0)
				(type default)
			)
			(fill no)
			(layer "F.CrtYd")
		)
		(fp_rect
			(start -3.556 3.5179)
			(end 3.556 -3.5179)
			(stroke
				(width 0)
				(type default)
			)
			(fill no)
			(layer "F.Fab")
		)
		(pad "1" smd rect
			(at 2.500122 -2.449322 180)
			(size 0.3048 1.1176)
			(layers "F.Cu" "F.Mask" "F.Paste")
			(net "P3V3_STBY_VFB")
		)
		(pad "2" smd rect
			(at 1.999996 -2.449322 180)
			(size 0.3048 1.1176)
			(layers "F.Cu" "F.Mask" "F.Paste")
			(net "P3V3_STBY_EN")
		)
		(pad "3" smd rect
			(at 1.500124 -2.449322 180)
			(size 0.3048 1.1176)
			(layers "F.Cu" "F.Mask" "F.Paste")
			(net "P3V3_STBY_PG")
		)
		(pad "4" smd rect
			(at 0.999998 -2.449322 180)
			(size 0.3048 1.1176)
			(layers "F.Cu" "F.Mask" "F.Paste")
			(net "P3V3_STBY_VBST")
		)
		(pad "5" smd rect
			(at 0.500126 -2.449322 180)
			(size 0.3048 1.1176)
			(layers "F.Cu" "F.Mask" "F.Paste")
			(net "P3V3_STBY_ROVP")
		)
		(pad "6" smd rect
			(at 0 -2.449322 180)
			(size 0.3048 1.1176)
			(layers "F.Cu" "F.Mask" "F.Paste")
			(net "P3V3_STBY_LL")
		)
		(pad "7" smd rect
			(at -0.500126 -2.449322 180)
			(size 0.3048 1.1176)
			(layers "F.Cu" "F.Mask" "F.Paste")
			(net "P3V3_STBY_LL")
		)
		(pad "8" smd rect
			(at -0.999998 -2.449322 180)
			(size 0.3048 1.1176)
			(layers "F.Cu" "F.Mask" "F.Paste")
			(net "P3V3_STBY_LL")
		)
		(pad "9" smd rect
			(at -1.500124 -2.449322 180)
			(size 0.3048 1.1176)
			(layers "F.Cu" "F.Mask" "F.Paste")
			(net "P3V3_STBY_LL")
		)
		(pad "10" smd rect
			(at -1.999996 -2.449322 180)
			(size 0.3048 1.1176)
			(layers "F.Cu" "F.Mask" "F.Paste")
			(net "P3V3_STBY_LL")
		)
		(pad "11" smd rect
			(at -2.500122 -2.449322 180)
			(size 0.3048 1.1176)
			(layers "F.Cu" "F.Mask" "F.Paste")
			(net "P3V3_STBY_LL")
		)
		(pad "12" smd rect
			(at -2.500122 2.449322 180)
			(size 0.3048 1.1176)
			(layers "F.Cu" "F.Mask" "F.Paste")
			(net "P3V3_STBY_VIN")
		)
		(pad "13" smd rect
			(at -1.999996 2.449322 180)
			(size 0.3048 1.1176)
			(layers "F.Cu" "F.Mask" "F.Paste")
			(net "P3V3_STBY_VIN")
		)
		(pad "14" smd rect
			(at -1.500124 2.449322 180)
			(size 0.3048 1.1176)
			(layers "F.Cu" "F.Mask" "F.Paste")
			(net "P3V3_STBY_VIN")
		)
		(pad "15" smd rect
			(at -0.999998 2.449322 180)
			(size 0.3048 1.1176)
			(layers "F.Cu" "F.Mask" "F.Paste")
			(net "P3V3_STBY_VIN")
		)
		(pad "16" smd rect
			(at -0.500126 2.449322 180)
			(size 0.3048 1.1176)
			(layers "F.Cu" "F.Mask" "F.Paste")
			(net "P3V3_STBY_VIN")
		)
		(pad "17" smd rect
			(at 0 2.449322 180)
			(size 0.3048 1.1176)
			(layers "F.Cu" "F.Mask" "F.Paste")
			(net "P3V3_STBY_VIN")
		)
		(pad "18" smd rect
			(at 0.500126 2.449322 180)
			(size 0.3048 1.1176)
			(layers "F.Cu" "F.Mask" "F.Paste")
			(net "P3V3_STBY_VREG")
		)
		(pad "19" smd rect
			(at 0.999998 2.449322 180)
			(size 0.3048 1.1176)
			(layers "F.Cu" "F.Mask" "F.Paste")
			(net "P3V3_STBY_VDD")
		)
		(pad "20" smd rect
			(at 1.500124 2.449322 180)
			(size 0.3048 1.1176)
			(layers "F.Cu" "F.Mask" "F.Paste")
			(net "P3V3_STBY_MODE")
		)
		(pad "21" smd rect
			(at 1.999996 2.449322 180)
			(size 0.3048 1.1176)
			(layers "F.Cu" "F.Mask" "F.Paste")
			(net "P3V3_STBY_TRIP")
		)
		(pad "22" smd rect
			(at 2.500122 2.449322 180)
			(size 0.3048 1.1176)
			(layers "F.Cu" "F.Mask" "F.Paste")
			(net "P3V3_STBY_RF")
		)
		(pad "23" smd custom
			(at 0 0 180)
			(size 0.83185 0.83185)
			(layers "F.Cu" "F.Mask" "F.Paste")
			(net "GND")
			(options
				(clearance outline)
				(anchor circle)
			)
			(primitives
				(gr_poly
					(pts
						(xy -2.7813 1.6637) (xy -2.7813 1.2954) (xy -3.048 1.2954) (xy -3.048 0.9525) (xy -2.7813 0.9525)
						(xy -2.7813 -0.9525) (xy -3.048 -0.9525) (xy -3.048 -1.2954) (xy -2.7813 -1.2954) (xy -2.7813 -1.6637)
						(xy 2.7813 -1.6637) (xy 2.7813 -1.2954) (xy 3.048 -1.2954) (xy 3.048 -0.9525) (xy 2.7813 -0.9525)
						(xy 2.7813 0.9525) (xy 3.048 0.9525) (xy 3.048 1.2954) (xy 2.7813 1.2954) (xy 2.7813 1.6637)
					)
					(width 0)
					(fill yes)
				)
			)
		)
	)
	(footprint ""
		(layer "F.Cu")
		(at 101.727 -67.4116 90)
		(property "Reference" "SR709"
			(at 0 0 90)
			(layer "F.SilkS")
			(hide yes)
			(effects
				(font
					(size 1.27 1.27)
				)
			)
		)
		(property "Value" "10R2F-L-GP"
			(at 0.064008 -3.993896 90)
			(unlocked yes)
			(layer "F.Fab")
			(hide yes)
			(effects
				(font
					(size 1.016 1.016)
					(thickness 0.1524)
				)
			)
		)
		(property "Device Type" "R402H14"
			(at 0.064008 -5.517896 90)
			(unlocked yes)
			(layer "F.Fab")
			(hide yes)
			(effects
				(font
					(size 1.016 1.016)
					(thickness 0.1524)
				)
			)
		)
		(duplicate_pad_numbers_are_jumpers no)
		(fp_line
			(start 0.508 -0.9398)
			(end -0.508 -0.9398)
			(stroke
				(width 0.1524)
				(type default)
			)
			(layer "F.SilkS")
		)
		(fp_line
			(start -0.508 -0.9398)
			(end -0.508 0.9398)
			(stroke
				(width 0.1524)
				(type default)
			)
			(layer "F.SilkS")
		)
		(fp_rect
			(start -0.508 0.9398)
			(end 0.508 -0.9398)
			(stroke
				(width 0)
				(type default)
			)
			(fill no)
			(layer "F.CrtYd")
		)
		(fp_rect
			(start -0.508 0.9398)
			(end 0.508 -0.9398)
			(stroke
				(width 0)
				(type default)
			)
			(fill no)
			(layer "F.Fab")
		)
		(pad "1" smd custom
			(at 0 -0.4445 90)
			(size 0.1397 0.1397)
			(layers "F.Cu" "F.Mask" "F.Paste")
			(net "P1V8_C")
			(options
				(clearance outline)
				(anchor circle)
			)
			(primitives
				(gr_poly
					(pts
						(arc
							(start -0.1778 -0.2794)
							(mid -0.249642 -0.249642)
							(end -0.2794 -0.1778)
						)
						(arc
							(start -0.2794 0.1778)
							(mid -0.249642 0.249642)
							(end -0.1778 0.2794)
						)
						(arc
							(start 0.1778 0.2794)
							(mid 0.249642 0.249642)
							(end 0.2794 0.1778)
						)
						(arc
							(start 0.2794 -0.1778)
							(mid 0.249642 -0.249642)
							(end 0.1778 -0.2794)
						)
					)
					(width 0)
					(fill yes)
				)
			)
		)
		(pad "2" smd custom
			(at 0 0.4445 90)
			(size 0.1397 0.1397)
			(layers "F.Cu" "F.Mask" "F.Paste")
			(net "HM40ADC_VDDA")
			(options
				(clearance outline)
				(anchor circle)
			)
			(primitives
				(gr_poly
					(pts
						(arc
							(start -0.1778 -0.2794)
							(mid -0.249642 -0.249642)
							(end -0.2794 -0.1778)
						)
						(arc
							(start -0.2794 0.1778)
							(mid -0.249642 0.249642)
							(end -0.1778 0.2794)
						)
						(arc
							(start 0.1778 0.2794)
							(mid 0.249642 0.249642)
							(end 0.2794 0.1778)
						)
						(arc
							(start 0.2794 -0.1778)
							(mid 0.249642 -0.249642)
							(end 0.1778 -0.2794)
						)
					)
					(width 0)
					(fill yes)
				)
			)
		)
	)
	(footprint ""
		(layer "F.Cu")
		(at 333.9338 -145.542 90)
		(property "Reference" "R7897"
			(at 0 0 90)
			(layer "F.SilkS")
			(hide yes)
			(effects
				(font
					(size 1.27 1.27)
				)
			)
		)
		(property "Value" "4K7R2F-GP"
			(at 0.064008 -3.993896 90)
			(unlocked yes)
			(layer "F.Fab")
			(hide yes)
			(effects
				(font
					(size 1.016 1.016)
					(thickness 0.1524)
				)
			)
		)
		(property "Device Type" "R402H16"
			(at 0.064008 -5.517896 90)
			(unlocked yes)
			(layer "F.Fab")
			(hide yes)
			(effects
				(font
					(size 1.016 1.016)
					(thickness 0.1524)
				)
			)
		)
		(duplicate_pad_numbers_are_jumpers no)
		(fp_line
			(start 0.508 -0.9398)
			(end -0.508 -0.9398)
			(stroke
				(width 0.1524)
				(type default)
			)
			(layer "F.SilkS")
		)
		(fp_line
			(start -0.508 -0.9398)
			(end -0.508 0.9398)
			(stroke
				(width 0.1524)
				(type default)
			)
			(layer "F.SilkS")
		)
		(fp_rect
			(start -0.508 0.9398)
			(end 0.508 -0.9398)
			(stroke
				(width 0)
				(type default)
			)
			(fill no)
			(layer "F.CrtYd")
		)
		(fp_rect
			(start -0.508 0.9398)
			(end 0.508 -0.9398)
			(stroke
				(width 0)
				(type default)
			)
			(fill no)
			(layer "F.Fab")
		)
		(pad "1" smd custom
			(at 0 -0.4445 90)
			(size 0.1397 0.1397)
			(layers "F.Cu" "F.Mask" "F.Paste")
			(net "P3V3_STBY")
			(options
				(clearance outline)
				(anchor circle)
			)
			(primitives
				(gr_poly
					(pts
						(arc
							(start -0.1778 -0.2794)
							(mid -0.249642 -0.249642)
							(end -0.2794 -0.1778)
						)
						(arc
							(start -0.2794 0.1778)
							(mid -0.249642 0.249642)
							(end -0.1778 0.2794)
						)
						(arc
							(start 0.1778 0.2794)
							(mid 0.249642 0.249642)
							(end 0.2794 0.1778)
						)
						(arc
							(start 0.2794 -0.1778)
							(mid 0.249642 -0.249642)
							(end 0.1778 -0.2794)
						)
					)
					(width 0)
					(fill yes)
				)
			)
		)
		(pad "2" smd custom
			(at 0 0.4445 90)
			(size 0.1397 0.1397)
			(layers "F.Cu" "F.Mask" "F.Paste")
			(net "USB_RESET_N")
			(options
				(clearance outline)
				(anchor circle)
			)
			(primitives
				(gr_poly
					(pts
						(arc
							(start -0.1778 -0.2794)
							(mid -0.249642 -0.249642)
							(end -0.2794 -0.1778)
						)
						(arc
							(start -0.2794 0.1778)
							(mid -0.249642 0.249642)
							(end -0.1778 0.2794)
						)
						(arc
							(start 0.1778 0.2794)
							(mid 0.249642 0.249642)
							(end 0.2794 0.1778)
						)
						(arc
							(start 0.2794 -0.1778)
							(mid 0.249642 -0.249642)
							(end 0.1778 -0.2794)
						)
					)
					(width 0)
					(fill yes)
				)
			)
		)
	)
)
